# T6G (Grand Teton) — schematic netlist excerpt (pin names and nets, part order shuffled) for the footprints in the layout excerpt that follows; sources: Cadence DE-HDL packaged netlist, KiCad conversion of 04192023_DAF0TMB3IC0_F0TG_MB_C_brd_V02_OCP.brd

L6  Q_INDUCTOR  100NH/16A IND  pkg SMLF  page 334 : \1\ = P0V9_CPU1_RT_2D ; \2\ = P0V9_CPU1_RT1_2A
R1123  Q_RES  1K 1% EMPTY  pkg 0201LF  page 310 : A = P1V8_CPU0_RT_1D ; B = RT_CPU0_P3_VQPS
PC2192  Q_CAP  0.001UF 50V 10% X7R  pkg C0402  page 262 : A = HSC_VTEMP ; B = AGND_HSC

(kicad_pcb
	(version 20260206)
	(generator "pcbnew")
	(generator_version "10.0")
	(general
		(thickness 1.6)
		(legacy_teardrops no)
	)
	(paper "A4")
	(title_block
		(title "04192023_DAF0TMB3IC0_F0TG_MB_C_brd_V02_OCP.brd")
		(comment 1 "Grand Teton / footprints 62-64 of 8354")
	)
	(layers
		(0 "F.Cu" signal "TOP")
		(4 "In1.Cu" signal "GND")
		(6 "In2.Cu" signal "IN1")
		(8 "In3.Cu" signal "GND1")
		(10 "In4.Cu" signal "IN2")
		(12 "In5.Cu" signal "GND2")
		(14 "In6.Cu" signal "IN3")
		(16 "In7.Cu" signal "GND3")
		(18 "In8.Cu" signal "VCC")
		(20 "In9.Cu" signal "VCC1")
		(22 "In10.Cu" signal "GND4")
		(24 "In11.Cu" signal "IN4")
		(26 "In12.Cu" signal "GND5")
		(28 "In13.Cu" signal "IN5")
		(30 "In14.Cu" signal "GND6")
		(32 "In15.Cu" signal "IN6")
		(34 "In16.Cu" signal "GND7")
		(2 "B.Cu" signal "BOTTOM")
		(9 "F.Adhes" user "F.Adhesive")
		(11 "B.Adhes" user "B.Adhesive")
		(13 "F.Paste" user "Package Geometry/Pastemask Top")
		(15 "B.Paste" user "Package Geometry/Pastemask Bottom")
		(5 "F.SilkS" user "Ref Des/Silkscreen Top")
		(7 "B.SilkS" user "Ref Des/Silkscreen Bottom")
		(1 "F.Mask" user "Board Geometry/Soldermask Top")
		(3 "B.Mask" user "Board Geometry/Soldermask Bottom")
		(17 "Dwgs.User" user "User.Drawings")
		(19 "Cmts.User" user "User.Comments")
		(21 "Eco1.User" user "User.Eco1")
		(23 "Eco2.User" user "User.Eco2")
		(25 "Edge.Cuts" user "Board Geometry/Outline")
		(27 "Margin" user)
		(31 "F.CrtYd" user "Package Geometry/Place Bound Top")
		(29 "B.CrtYd" user "Package Geometry/Place Bound Bottom")
		(35 "F.Fab" user "Ref Des/Assembly Top")
		(33 "B.Fab" user "Ref Des/Assembly Bottom")
	)
	(footprint ""
		(layer "F.Cu")
		(at 73.15073 -392.521694)
		(property "Reference" "L6"
			(at -2.3876 -2.969768 0)
			(unlocked yes)
			(layer "F.SilkS")
			(effects
				(font
					(size 0.7874 0.5842)
					(thickness 0.1524)
				)
				(justify left)
			)
		)
		(property "Value" ""
			(at 0 0 0)
			(layer "F.Fab")
			(effects
				(font
					(size 1.27 1.27)
				)
			)
		)
		(duplicate_pad_numbers_are_jumpers no)
		(fp_line
			(start -2.249932 -2.249932)
			(end 2.249932 -2.249932)
			(stroke
				(width 0.1524)
				(type default)
			)
			(layer "F.SilkS")
		)
		(fp_line
			(start -2.249932 -1.3843)
			(end -2.249932 -2.249932)
			(stroke
				(width 0.1524)
				(type default)
			)
			(layer "F.SilkS")
		)
		(fp_line
			(start -2.249932 2.249932)
			(end -2.249932 1.3843)
			(stroke
				(width 0.1524)
				(type default)
			)
			(layer "F.SilkS")
		)
		(fp_line
			(start 2.249932 -2.249932)
			(end 2.249932 -1.3843)
			(stroke
				(width 0.1524)
				(type default)
			)
			(layer "F.SilkS")
		)
		(fp_line
			(start 2.249932 1.3843)
			(end 2.249932 2.249932)
			(stroke
				(width 0.1524)
				(type default)
			)
			(layer "F.SilkS")
		)
		(fp_line
			(start 2.249932 2.249932)
			(end -2.249932 2.249932)
			(stroke
				(width 0.1524)
				(type default)
			)
			(layer "F.SilkS")
		)
		(fp_line
			(start -2.249932 -2.249932)
			(end 2.249932 -2.249932)
			(stroke
				(width 0.1)
				(type default)
			)
			(layer "F.Fab")
		)
		(fp_line
			(start -2.249932 2.249932)
			(end -2.249932 -2.249932)
			(stroke
				(width 0.1)
				(type default)
			)
			(layer "F.Fab")
		)
		(fp_line
			(start 2.249932 -2.249932)
			(end 2.249932 2.249932)
			(stroke
				(width 0.1)
				(type default)
			)
			(layer "F.Fab")
		)
		(fp_line
			(start 2.249932 2.249932)
			(end -2.249932 2.249932)
			(stroke
				(width 0.1)
				(type default)
			)
			(layer "F.Fab")
		)
		(pad "1" smd rect
			(at -1.82499 0)
			(size 1.0668 2.5146)
			(layers "F.Cu" "F.Mask" "F.Paste")
			(net "P0V9_CPU1_RT_2D")
		)
		(pad "2" smd rect
			(at 1.82499 0)
			(size 1.0668 2.5146)
			(layers "F.Cu" "F.Mask" "F.Paste")
			(net "P0V9_CPU1_RT1_2A")
		)
	)
	(footprint ""
		(layer "F.Cu")
		(at 178.689 -405.511 180)
		(property "Reference" "PC2192"
			(at 0 0 180)
			(layer "F.SilkS")
			(hide yes)
			(effects
				(font
					(size 1.27 1.27)
				)
			)
		)
		(property "Value" ""
			(at 0 0 180)
			(layer "F.Fab")
			(effects
				(font
					(size 1.27 1.27)
				)
			)
		)
		(duplicate_pad_numbers_are_jumpers no)
		(fp_line
			(start 0.7874 0.4064)
			(end -0.7874 0.4064)
			(stroke
				(width 0.1524)
				(type default)
			)
			(layer "F.SilkS")
		)
		(fp_line
			(start 0.7874 -0.4064)
			(end 0.7874 0.4064)
			(stroke
				(width 0.1524)
				(type default)
			)
			(layer "F.SilkS")
		)
		(fp_line
			(start -0.7874 0.4064)
			(end -0.7874 -0.4064)
			(stroke
				(width 0.1524)
				(type default)
			)
			(layer "F.SilkS")
		)
		(fp_line
			(start -0.7874 -0.4064)
			(end 0.7874 -0.4064)
			(stroke
				(width 0.1524)
				(type default)
			)
			(layer "F.SilkS")
		)
		(fp_line
			(start 0.67945 0.3048)
			(end 0.120396 0.3048)
			(stroke
				(width 0.1)
				(type default)
			)
			(layer "F.Fab")
		)
		(fp_line
			(start 0.67945 -0.3048)
			(end 0.67945 0.3048)
			(stroke
				(width 0.1)
				(type default)
			)
			(layer "F.Fab")
		)
		(fp_line
			(start 0.12065 -0.2794)
			(end 0.12065 -0.3048)
			(stroke
				(width 0.1)
				(type default)
			)
			(layer "F.Fab")
		)
		(fp_line
			(start 0.12065 -0.3048)
			(end 0.67945 -0.3048)
			(stroke
				(width 0.1)
				(type default)
			)
			(layer "F.Fab")
		)
		(fp_line
			(start 0.120396 0.3048)
			(end 0.120396 0.2794)
			(stroke
				(width 0.1)
				(type default)
			)
			(layer "F.Fab")
		)
		(fp_line
			(start 0.120396 0.2794)
			(end -0.12065 0.2794)
			(stroke
				(width 0.1)
				(type default)
			)
			(layer "F.Fab")
		)
		(fp_line
			(start -0.12065 0.3048)
			(end -0.67945 0.3048)
			(stroke
				(width 0.1)
				(type default)
			)
			(layer "F.Fab")
		)
		(fp_line
			(start -0.12065 0.2794)
			(end -0.12065 0.3048)
			(stroke
				(width 0.1)
				(type default)
			)
			(layer "F.Fab")
		)
		(fp_line
			(start -0.12065 -0.2794)
			(end 0.12065 -0.2794)
			(stroke
				(width 0.1)
				(type default)
			)
			(layer "F.Fab")
		)
		(fp_line
			(start -0.12065 -0.305054)
			(end -0.12065 -0.2794)
			(stroke
				(width 0.1)
				(type default)
			)
			(layer "F.Fab")
		)
		(fp_line
			(start -0.67945 0.3048)
			(end -0.67945 -0.305054)
			(stroke
				(width 0.1)
				(type default)
			)
			(layer "F.Fab")
		)
		(fp_line
			(start -0.67945 -0.305054)
			(end -0.12065 -0.305054)
			(stroke
				(width 0.1)
				(type default)
			)
			(layer "F.Fab")
		)
		(pad "1" smd circle
			(at -0.40005 0 180)
			(size 0 0)
			(layers "F.Cu" "F.Mask" "F.Paste")
			(net "HSC_VTEMP")
		)
		(pad "2" smd circle
			(at 0.40005 0 180)
			(size 0 0)
			(layers "F.Cu" "F.Mask" "F.Paste")
			(net "AGND_HSC")
		)
	)
	(footprint ""
		(layer "F.Cu")
		(at 389.653018 -404.0124 -90)
		(property "Reference" "R1123"
			(at 0 0 270)
			(layer "F.SilkS")
			(hide yes)
			(effects
				(font
					(size 1.27 1.27)
				)
			)
		)
		(property "Value" ""
			(at 0 0 270)
			(layer "F.Fab")
			(effects
				(font
					(size 1.27 1.27)
				)
			)
		)
		(duplicate_pad_numbers_are_jumpers no)
		(fp_line
			(start -0.32512 0.175006)
			(end -0.32512 -0.175006)
			(stroke
				(width 0.1)
				(type default)
			)
			(layer "F.Fab")
		)
		(fp_line
			(start 0.32512 0.175006)
			(end -0.32512 0.175006)
			(stroke
				(width 0.1)
				(type default)
			)
			(layer "F.Fab")
		)
		(fp_line
			(start -0.32512 -0.175006)
			(end 0.32512 -0.175006)
			(stroke
				(width 0.1)
				(type default)
			)
			(layer "F.Fab")
		)
		(fp_line
			(start 0.32512 -0.175006)
			(end 0.32512 0.175006)
			(stroke
				(width 0.1)
				(type default)
			)
			(layer "F.Fab")
		)
		(pad "1" smd rect
			(at -0.2667 0 270)
			(size 0.3048 0.381)
			(layers "F.Cu" "F.Mask" "F.Paste")
			(net "P1V8_CPU0_RT_1D")
		)
		(pad "2" smd rect
			(at 0.2667 0 90)
			(size 0.3048 0.381)
			(layers "F.Cu" "F.Mask" "F.Paste")
			(net "RT_CPU0_P3_VQPS")
		)
	)
)
